(kicad_pcb
	(version 20241229)
	(generator "pcbnew")
	(generator_version "9.0")
	(general
		(thickness 1.711)
		(legacy_teardrops no)
	)
	(paper "A4")
	(title_block
		(title "Antmicro Baseboard for Jetson AGX Thor")
		(date "2026-02-18")
		(rev "1.1.0")
		(company "Antmicro Ltd")
		(comment 1 "www.antmicro.com")
		(comment 9 "footprints 38-41 of 1170")
	)
	(layers
		(0 "F.Cu" signal)
		(4 "In1.Cu" signal)
		(6 "In2.Cu" signal)
		(8 "In3.Cu" signal)
		(10 "In4.Cu" jumper)
		(12 "In5.Cu" signal)
		(14 "In6.Cu" signal)
		(16 "In7.Cu" signal)
		(18 "In8.Cu" signal)
		(2 "B.Cu" signal)
		(9 "F.Adhes" user "F.Adhesive")
		(11 "B.Adhes" user "B.Adhesive")
		(13 "F.Paste" user)
		(15 "B.Paste" user)
		(5 "F.SilkS" user "F.Silkscreen")
		(7 "B.SilkS" user "B.Silkscreen")
		(1 "F.Mask" user)
		(3 "B.Mask" user)
		(17 "Dwgs.User" user "User.Drawings")
		(19 "Cmts.User" user "User.Comments")
		(21 "Eco1.User" user "User.Eco1")
		(23 "Eco2.User" user "User.Eco2")
		(25 "Edge.Cuts" user)
		(27 "Margin" user)
		(31 "F.CrtYd" user "F.Courtyard")
		(29 "B.CrtYd" user "B.Courtyard")
		(35 "F.Fab" user)
		(33 "B.Fab" user)
	)
	(footprint "antmicro-footprints:R_0402_1005Metric"
		(layer "F.Cu")
		(at 92.7 119.1 180)
		(descr "Resistor SMD 0402")
		(tags "resistor SMD 0402")
		(property "Reference" "R351"
			(at -1.1 0.5 180)
			(layer "F.SilkS")
			(effects
				(font
					(size 0.7 0.7)
					(thickness 0.15)
				)
				(justify left bottom)
			)
		)
		(property "Value" "R_0R_0402"
			(at -1.011843 1.772046 180)
			(layer "F.Fab")
			(effects
				(font
					(size 0.7 0.7)
					(thickness 0.15)
				)
				(justify left bottom)
			)
		)
		(property "Datasheet" "https://industrial.panasonic.com/cdbs/www-data/pdf/RDA0000/AOA0000C301.pdf"
			(at 0 0 180)
			(layer "F.Fab")
			(hide yes)
			(effects
				(font
					(size 1.27 1.27)
					(thickness 0.15)
				)
			)
		)
		(property "Description" "SMD Chip Resistor, Jumper, 0 ohm, 100 mW, 0402 [1005 Metric], Thick Film, General Purpose"
			(at 0 0 180)
			(layer "F.Fab")
			(hide yes)
			(effects
				(font
					(size 1.27 1.27)
					(thickness 0.15)
				)
			)
		)
		(property "MPN" "ERJ2GE0R00X"
			(at 0 0 180)
			(unlocked yes)
			(layer "F.Fab")
			(hide yes)
			(effects
				(font
					(size 1 1)
					(thickness 0.15)
				)
			)
		)
		(property "Manufacturer" "Panasonic"
			(at 0 0 180)
			(unlocked yes)
			(layer "F.Fab")
			(hide yes)
			(effects
				(font
					(size 1 1)
					(thickness 0.15)
				)
			)
		)
		(property "License" "Apache-2.0"
			(at 0 0 180)
			(unlocked yes)
			(layer "F.Fab")
			(hide yes)
			(effects
				(font
					(size 1 1)
					(thickness 0.15)
				)
			)
		)
		(property "Author" "Antmicro"
			(at 0 0 180)
			(unlocked yes)
			(layer "F.Fab")
			(hide yes)
			(effects
				(font
					(size 1 1)
					(thickness 0.15)
				)
			)
		)
		(property "Val" "0R"
			(at 0 0 180)
			(unlocked yes)
			(layer "F.Fab")
			(hide yes)
			(effects
				(font
					(size 1 1)
					(thickness 0.15)
				)
			)
		)
		(property "Tolerance" "~"
			(at 0 0 180)
			(unlocked yes)
			(layer "F.Fab")
			(hide yes)
			(effects
				(font
					(size 1 1)
					(thickness 0.15)
				)
			)
		)
		(property "Current" "1A"
			(at 0 0 180)
			(unlocked yes)
			(layer "F.Fab")
			(hide yes)
			(effects
				(font
					(size 1 1)
					(thickness 0.15)
				)
			)
		)
		(sheetname "/Expansion connector/")
		(sheetfile "expansion_connector.kicad_sch")
		(attr smd)
		(fp_poly
			(pts
				(xy -0.925 -0.47) (xy 0.925 -0.47) (xy 0.925 0.47) (xy -0.925 0.47)
			)
			(stroke
				(width 0.05)
				(type default)
			)
			(fill no)
			(layer "F.CrtYd")
		)
		(fp_poly
			(pts
				(xy -0.5 -0.25) (xy 0.5 -0.25) (xy 0.5 0.25) (xy -0.5 0.25)
			)
			(stroke
				(width 0.15)
				(type solid)
			)
			(fill no)
			(layer "F.Fab")
		)
		(fp_text user "${REFERENCE}"
			(at -0.95 3.168 180)
			(layer "F.Fab")
			(effects
				(font
					(size 0.7 0.7)
					(thickness 0.15)
				)
				(justify left bottom)
			)
		)
		(fp_text user "Author: Antmicro"
			(at -0.95 4.169 180)
			(layer "F.Fab")
			(effects
				(font
					(size 0.7 0.7)
					(thickness 0.15)
				)
				(justify left bottom)
			)
		)
		(fp_text user "License: Apache-2.0"
			(at -0.949999 5.169 180)
			(layer "F.Fab")
			(effects
				(font
					(size 0.7 0.7)
					(thickness 0.15)
				)
				(justify left bottom)
			)
		)
		(pad "1" smd roundrect
			(at -0.48 0 180)
			(size 0.59 0.64)
			(layers "F.Cu" "F.Mask" "F.Paste")
			(roundrect_rratio 0.25)
			(net 790 "/Expansion connector/PCIe_{C2x1}.RX0+")
			(pintype "passive")
		)
		(pad "2" smd roundrect
			(at 0.48 0 180)
			(size 0.59 0.64)
			(layers "F.Cu" "F.Mask" "F.Paste")
			(roundrect_rratio 0.25)
			(net 471 "/Expansion connector/PER0_C2_N")
			(pintype "passive")
		)
	)
	(footprint "antmicro-footprints:R_0402_1005Metric"
		(layer "F.Cu")
		(at 156.72 113.2 180)
		(descr "Resistor SMD 0402")
		(tags "resistor SMD 0402")
		(property "Reference" "R375"
			(at -3.68 0.4 0)
			(layer "F.SilkS")
			(effects
				(font
					(size 0.7 0.7)
					(thickness 0.15)
				)
				(justify right top)
			)
		)
		(property "Value" "R_2k2_0402"
			(at -1.011843 1.772047 0)
			(layer "F.Fab")
			(effects
				(font
					(size 0.7 0.7)
					(thickness 0.15)
				)
				(justify right top)
			)
		)
		(property "Datasheet" "https://www.bourns.com/docs/product-datasheets/cr.pdf"
			(at 0 0 0)
			(layer "F.Fab")
			(hide yes)
			(effects
				(font
					(size 1.27 1.27)
					(thickness 0.15)
				)
			)
		)
		(property "Description" "SMD Chip Resistor, 2.2 kohm, ± 1%, 62.5 mW, 0402 [1005 Metric], Thick Film, General Purpose"
			(at 0 0 0)
			(layer "F.Fab")
			(hide yes)
			(effects
				(font
					(size 1.27 1.27)
					(thickness 0.15)
				)
			)
		)
		(property "MPN" "CR0402-FX-2201GLF"
			(at 0 0 180)
			(unlocked yes)
			(layer "F.Fab")
			(hide yes)
			(effects
				(font
					(size 1 1)
					(thickness 0.15)
				)
			)
		)
		(property "Manufacturer" "Bourns"
			(at 0 0 180)
			(unlocked yes)
			(layer "F.Fab")
			(hide yes)
			(effects
				(font
					(size 1 1)
					(thickness 0.15)
				)
			)
		)
		(property "License" "Apache-2.0"
			(at 0 0 180)
			(unlocked yes)
			(layer "F.Fab")
			(hide yes)
			(effects
				(font
					(size 1 1)
					(thickness 0.15)
				)
			)
		)
		(property "Author" "Antmicro"
			(at 0 0 180)
			(unlocked yes)
			(layer "F.Fab")
			(hide yes)
			(effects
				(font
					(size 1 1)
					(thickness 0.15)
				)
			)
		)
		(property "Val" "2k2"
			(at 0 0 180)
			(unlocked yes)
			(layer "F.Fab")
			(hide yes)
			(effects
				(font
					(size 1 1)
					(thickness 0.15)
				)
			)
		)
		(property "Tolerance" "1%"
			(at 0 0 180)
			(unlocked yes)
			(layer "F.Fab")
			(hide yes)
			(effects
				(font
					(size 1 1)
					(thickness 0.15)
				)
			)
		)
		(sheetname "/SoM_IO/")
		(sheetfile "som_io.kicad_sch")
		(attr smd)
		(fp_rect
			(start -0.925 -0.47)
			(end 0.925 0.47)
			(stroke
				(width 0.05)
				(type default)
			)
			(fill no)
			(layer "F.CrtYd")
		)
		(fp_rect
			(start -0.5 -0.25)
			(end 0.5 0.25)
			(stroke
				(width 0.15)
				(type solid)
			)
			(fill no)
			(layer "F.Fab")
		)
		(fp_text user "Author: Antmicro"
			(at -0.95 4.169 0)
			(layer "F.Fab")
			(effects
				(font
					(size 0.7 0.7)
					(thickness 0.15)
				)
				(justify right top)
			)
		)
		(fp_text user "License: Apache-2.0"
			(at -0.95 5.169 0)
			(layer "F.Fab")
			(effects
				(font
					(size 0.7 0.7)
					(thickness 0.15)
				)
				(justify right top)
			)
		)
		(fp_text user "${REFERENCE}"
			(at -0.95 3.168 0)
			(layer "F.Fab")
			(effects
				(font
					(size 0.7 0.7)
					(thickness 0.15)
				)
				(justify right top)
			)
		)
		(pad "1" smd roundrect
			(at -0.48 0 180)
			(size 0.59 0.64)
			(layers "F.Cu" "F.Mask" "F.Paste")
			(roundrect_rratio 0.25)
			(net 2 "+3V3")
			(pintype "passive")
		)
		(pad "2" smd roundrect
			(at 0.48 0 180)
			(size 0.59 0.64)
			(layers "F.Cu" "F.Mask" "F.Paste")
			(roundrect_rratio 0.25)
			(net 42 "/Peripherals/I2C_{CONN}.SCL")
			(pintype "passive")
		)
	)
	(footprint "antmicro-footprints:R_0402_1005Metric"
		(layer "F.Cu")
		(at 179.949468 66.47 -90)
		(descr "Resistor SMD 0402")
		(tags "resistor SMD 0402")
		(property "Reference" "R29"
			(at -3.01 0.3 90)
			(layer "F.SilkS")
			(effects
				(font
					(size 0.7 0.7)
					(thickness 0.15)
				)
				(justify right top)
			)
		)
		(property "Value" "R_100k_0402"
			(at -1.011843 1.772047 90)
			(layer "F.Fab")
			(effects
				(font
					(size 0.7 0.7)
					(thickness 0.15)
				)
				(justify right top)
			)
		)
		(property "Datasheet" "https://www.bourns.com/docs/product-datasheets/cr.pdf"
			(at 0 0 90)
			(layer "F.Fab")
			(hide yes)
			(effects
				(font
					(size 1.27 1.27)
					(thickness 0.15)
				)
			)
		)
		(property "Description" "SMD Chip Resistor, 100 kohm, ± 1%, 62.5 mW, 0402 [1005 Metric], Thick Film, General Purpose"
			(at 0 0 90)
			(layer "F.Fab")
			(hide yes)
			(effects
				(font
					(size 1.27 1.27)
					(thickness 0.15)
				)
			)
		)
		(property "MPN" "CR0402-FX-1003GLF"
			(at 0 0 90)
			(unlocked yes)
			(layer "F.Fab")
			(hide yes)
			(effects
				(font
					(size 1 1)
					(thickness 0.15)
				)
			)
		)
		(property "Manufacturer" "Bourns"
			(at 0 0 90)
			(unlocked yes)
			(layer "F.Fab")
			(hide yes)
			(effects
				(font
					(size 1 1)
					(thickness 0.15)
				)
			)
		)
		(property "License" "Apache-2.0"
			(at 0 0 90)
			(unlocked yes)
			(layer "F.Fab")
			(hide yes)
			(effects
				(font
					(size 1 1)
					(thickness 0.15)
				)
			)
		)
		(property "Author" "Antmicro"
			(at 0 0 90)
			(unlocked yes)
			(layer "F.Fab")
			(hide yes)
			(effects
				(font
					(size 1 1)
					(thickness 0.15)
				)
			)
		)
		(property "Val" "100k"
			(at 0 0 90)
			(unlocked yes)
			(layer "F.Fab")
			(hide yes)
			(effects
				(font
					(size 1 1)
					(thickness 0.15)
				)
			)
		)
		(property "Tolerance" "1%"
			(at 0 0 90)
			(unlocked yes)
			(layer "F.Fab")
			(hide yes)
			(effects
				(font
					(size 1 1)
					(thickness 0.15)
				)
			)
		)
		(component_classes
			(class "DCDC_20V")
		)
		(sheetname "/DCDC/")
		(sheetfile "dcdc.kicad_sch")
		(attr smd)
		(fp_rect
			(start -0.925 -0.47)
			(end 0.925 0.47)
			(stroke
				(width 0.05)
				(type default)
			)
			(fill no)
			(layer "F.CrtYd")
		)
		(fp_rect
			(start -0.5 -0.25)
			(end 0.5 0.25)
			(stroke
				(width 0.15)
				(type solid)
			)
			(fill no)
			(layer "F.Fab")
		)
		(fp_text user "${REFERENCE}"
			(at -0.95 3.168 90)
			(layer "F.Fab")
			(effects
				(font
					(size 0.7 0.7)
					(thickness 0.15)
				)
				(justify right top)
			)
		)
		(fp_text user "Author: Antmicro"
			(at -0.95 4.169 90)
			(layer "F.Fab")
			(effects
				(font
					(size 0.7 0.7)
					(thickness 0.15)
				)
				(justify right top)
			)
		)
		(fp_text user "License: Apache-2.0"
			(at -0.95 5.169 90)
			(layer "F.Fab")
			(effects
				(font
					(size 0.7 0.7)
					(thickness 0.15)
				)
				(justify right top)
			)
		)
		(pad "1" smd roundrect
			(at -0.48 0 270)
			(size 0.59 0.64)
			(layers "F.Cu" "F.Mask" "F.Paste")
			(roundrect_rratio 0.25)
			(net 1 "GND")
			(pintype "passive")
		)
		(pad "2" smd roundrect
			(at 0.48 0 270)
			(size 0.59 0.64)
			(layers "F.Cu" "F.Mask" "F.Paste")
			(roundrect_rratio 0.25)
			(net 1208 "/DCDC/20V_MODE1")
			(pintype "passive")
		)
	)
	(footprint "antmicro-footprints:USON-10_2.5x1mm_P0.5mm"
		(layer "F.Cu")
		(at 221.369 105.46 180)
		(descr "USON-10 2.5x1mm_ Pitch 0.5mm")
		(tags "USON-10 2.5x1mm Pitch 0.5mm")
		(property "Reference" "U57"
			(at -1.081 0.96 90)
			(layer "F.SilkS")
			(effects
				(font
					(size 0.7 0.7)
					(thickness 0.15)
				)
				(justify right top)
			)
		)
		(property "Value" "TPD4E05U06QDQARQ1"
			(at 0.018 2.499 0)
			(layer "F.Fab")
			(effects
				(font
					(size 0.7 0.7)
					(thickness 0.15)
				)
				(justify right top)
			)
		)
		(property "Datasheet" "https://www.ti.com/lit/ds/symlink/tpd4e05u06-q1.pdf?HQS=dis-mous-null-mousermode-dsf-pf-null-wwe&ts=1663591265741&ref_url=https%253A%252F%252Fwww.mouser.com%252F"
			(at 0 0 0)
			(layer "F.Fab")
			(hide yes)
			(effects
				(font
					(size 1.27 1.27)
					(thickness 0.15)
				)
			)
		)
		(property "Description" "TVS diode array, 12 kV, USON-10, 5.5 V, 0.5 pF"
			(at 0 0 0)
			(layer "F.Fab")
			(hide yes)
			(effects
				(font
					(size 1.27 1.27)
					(thickness 0.15)
				)
			)
		)
		(property "Manufacturer" "Texas Instruments"
			(at 0 0 180)
			(unlocked yes)
			(layer "F.Fab")
			(hide yes)
			(effects
				(font
					(size 1 1)
					(thickness 0.15)
				)
			)
		)
		(property "MPN" "TPD4E05U06QDQARQ1"
			(at 0 0 180)
			(unlocked yes)
			(layer "F.Fab")
			(hide yes)
			(effects
				(font
					(size 1 1)
					(thickness 0.15)
				)
			)
		)
		(property "Author" "Antmicro"
			(at 0 0 180)
			(unlocked yes)
			(layer "F.Fab")
			(hide yes)
			(effects
				(font
					(size 1 1)
					(thickness 0.15)
				)
			)
		)
		(property "License" "Apache-2.0"
			(at 0 0 180)
			(unlocked yes)
			(layer "F.Fab")
			(hide yes)
			(effects
				(font
					(size 1 1)
					(thickness 0.15)
				)
			)
		)
		(sheetname "/Recovery USB/")
		(sheetfile "recovery_usb.kicad_sch")
		(attr smd)
		(fp_line
			(start 0.498 1.398)
			(end -0.5 1.398)
			(stroke
				(width 0.15)
				(type solid)
			)
			(layer "F.SilkS")
		)
		(fp_line
			(start 0.498 -1.401)
			(end -0.5 -1.401)
			(stroke
				(width 0.15)
				(type solid)
			)
			(layer "F.SilkS")
		)
		(fp_circle
			(center -0.68 -1.27)
			(end -0.63 -1.27)
			(stroke
				(width 0.15)
				(type solid)
			)
			(fill yes)
			(layer "F.SilkS")
		)
		(fp_rect
			(start -0.8 -1.5)
			(end 0.8 1.499)
			(stroke
				(width 0.05)
				(type solid)
			)
			(fill no)
			(layer "F.CrtYd")
		)
		(fp_line
			(start 0.498 -1.25)
			(end 0.498 1.249)
			(stroke
				(width 0.15)
				(type solid)
			)
			(layer "F.Fab")
		)
		(fp_line
			(start 0.498 -1.25)
			(end -0.25 -1.25)
			(stroke
				(width 0.15)
				(type solid)
			)
			(layer "F.Fab")
		)
		(fp_line
			(start -0.25 -1.25)
			(end -0.5 -1)
			(stroke
				(width 0.15)
				(type solid)
			)
			(layer "F.Fab")
		)
		(fp_line
			(start -0.5 1.249)
			(end 0.498 1.249)
			(stroke
				(width 0.15)
				(type solid)
			)
			(layer "F.Fab")
		)
		(fp_line
			(start -0.5 -1)
			(end -0.5 1.249)
			(stroke
				(width 0.15)
				(type solid)
			)
			(layer "F.Fab")
		)
		(fp_text user "Author: Antmicro"
			(at -0.802 5.7 0)
			(layer "F.Fab")
			(effects
				(font
					(size 0.7 0.7)
					(thickness 0.15)
				)
				(justify right top)
			)
		)
		(fp_text user "License: Apache-2.0"
			(at -0.802 6.9 0)
			(layer "F.Fab")
			(effects
				(font
					(size 0.7 0.7)
					(thickness 0.15)
				)
				(justify right top)
			)
		)
		(fp_text user "${REFERENCE}"
			(at -0.802 4.498 0)
			(layer "F.Fab")
			(effects
				(font
					(size 0.7 0.7)
					(thickness 0.15)
				)
				(justify right top)
			)
		)
		(pad "1" smd roundrect
			(at -0.387 -1 90)
			(size 0.25 0.55)
			(layers "F.Cu" "F.Mask" "F.Paste")
			(roundrect_rratio 0.25)
			(net 800 "/Recovery USB/USBC2_RX1_N")
			(pintype "passive")
		)
		(pad "2" smd roundrect
			(at -0.387 -0.5 90)
			(size 0.25 0.55)
			(layers "F.Cu" "F.Mask" "F.Paste")
			(roundrect_rratio 0.25)
			(net 802 "/Recovery USB/USBC2_RX1_P")
			(pintype "passive")
		)
		(pad "3" smd roundrect
			(at -0.387 0 90)
			(size 0.4 0.55)
			(layers "F.Cu" "F.Mask" "F.Paste")
			(roundrect_rratio 0.25)
			(net 1 "GND")
			(pintype "power_in")
		)
		(pad "4" smd roundrect
			(at -0.387 0.498 90)
			(size 0.25 0.55)
			(layers "F.Cu" "F.Mask" "F.Paste")
			(roundrect_rratio 0.25)
			(net 215 "/Recovery USB/USBC2_CONN_TX1_N")
			(pintype "passive")
		)
		(pad "5" smd roundrect
			(at -0.387 0.998 90)
			(size 0.25 0.55)
			(layers "F.Cu" "F.Mask" "F.Paste")
			(roundrect_rratio 0.25)
			(net 245 "/Recovery USB/USBC2_CONN_TX1_P")
			(pintype "passive")
		)
		(pad "6" smd roundrect
			(at 0.385 0.998 90)
			(size 0.25 0.55)
			(layers "F.Cu" "F.Mask" "F.Paste")
			(roundrect_rratio 0.25)
			(net 245 "/Recovery USB/USBC2_CONN_TX1_P")
			(pintype "passive")
		)
		(pad "7" smd roundrect
			(at 0.385 0.498 90)
			(size 0.25 0.55)
			(layers "F.Cu" "F.Mask" "F.Paste")
			(roundrect_rratio 0.25)
			(net 215 "/Recovery USB/USBC2_CONN_TX1_N")
			(pintype "passive")
		)
		(pad "8" smd roundrect
			(at 0.385 0 90)
			(size 0.4 0.55)
			(layers "F.Cu" "F.Mask" "F.Paste")
			(roundrect_rratio 0.25)
			(net 1 "GND")
			(pintype "passive")
		)
		(pad "9" smd roundrect
			(at 0.385 -0.5 90)
			(size 0.25 0.55)
			(layers "F.Cu" "F.Mask" "F.Paste")
			(roundrect_rratio 0.25)
			(net 802 "/Recovery USB/USBC2_RX1_P")
			(pintype "passive")
		)
		(pad "10" smd roundrect
			(at 0.385 -1 90)
			(size 0.25 0.55)
			(layers "F.Cu" "F.Mask" "F.Paste")
			(roundrect_rratio 0.25)
			(net 800 "/Recovery USB/USBC2_RX1_N")
			(pintype "passive")
		)
	)
)
